(kicad_pcb
	(version 20260206)
	(generator "pcbnew")
	(generator_version "10.0")
	(general
		(thickness 1.6)
		(legacy_teardrops no)
	)
	(paper "A4")
	(title_block
		(title "01162023_DA0F0TEBIF0_F0T_Expander_BD_F_brd_V02_OCP.brd")
		(comment 1 "Grand Teton / footprints 946-950 of 9728")
	)
	(layers
		(0 "F.Cu" signal "TOP")
		(4 "In1.Cu" signal "GND")
		(6 "In2.Cu" signal "VCC")
		(8 "In3.Cu" signal "VCC1")
		(10 "In4.Cu" signal "GND1")
		(12 "In5.Cu" signal "IN1")
		(14 "In6.Cu" signal "GND2")
		(16 "In7.Cu" signal "IN2")
		(18 "In8.Cu" signal "GND3")
		(20 "In9.Cu" signal "IN3")
		(22 "In10.Cu" signal "GND4")
		(24 "In11.Cu" signal "IN4")
		(26 "In12.Cu" signal "GND5")
		(28 "In13.Cu" signal "IN5")
		(30 "In14.Cu" signal "GND6")
		(32 "In15.Cu" signal "IN6")
		(34 "In16.Cu" signal "GND7")
		(2 "B.Cu" signal "BOTTOM")
		(9 "F.Adhes" user "F.Adhesive")
		(11 "B.Adhes" user "B.Adhesive")
		(13 "F.Paste" user "Package Geometry/Pastemask Top")
		(15 "B.Paste" user "Package Geometry/Pastemask Bottom")
		(5 "F.SilkS" user "Ref Des/Silkscreen Top")
		(7 "B.SilkS" user "Ref Des/Silkscreen Bottom")
		(1 "F.Mask" user "Board Geometry/Soldermask Top")
		(3 "B.Mask" user "Board Geometry/Soldermask Bottom")
		(17 "Dwgs.User" user "User.Drawings")
		(19 "Cmts.User" user "User.Comments")
		(21 "Eco1.User" user "User.Eco1")
		(23 "Eco2.User" user "User.Eco2")
		(25 "Edge.Cuts" user "Board Geometry/Outline")
		(27 "Margin" user)
		(31 "F.CrtYd" user "Package Geometry/Place Bound Top")
		(29 "B.CrtYd" user "Package Geometry/Place Bound Bottom")
		(35 "F.Fab" user "Ref Des/Assembly Top")
		(33 "B.Fab" user "Ref Des/Assembly Bottom")
	)
	(footprint ""
		(layer "F.Cu")
		(at 405.892 -383.667 90)
		(property "Reference" "R6280"
			(at 0 0 90)
			(layer "F.SilkS")
			(hide yes)
			(effects
				(font
					(size 1.27 1.27)
				)
			)
		)
		(property "Value" ""
			(at 0 0 90)
			(layer "F.Fab")
			(effects
				(font
					(size 1.27 1.27)
				)
			)
		)
		(duplicate_pad_numbers_are_jumpers no)
		(fp_line
			(start 0.7874 -0.4064)
			(end 0.7874 0.4064)
			(stroke
				(width 0.1524)
				(type default)
			)
			(layer "F.SilkS")
		)
		(fp_line
			(start -0.7874 -0.4064)
			(end 0.7874 -0.4064)
			(stroke
				(width 0.1524)
				(type default)
			)
			(layer "F.SilkS")
		)
		(fp_line
			(start 0.7874 0.4064)
			(end -0.7874 0.4064)
			(stroke
				(width 0.1524)
				(type default)
			)
			(layer "F.SilkS")
		)
		(fp_line
			(start -0.7874 0.4064)
			(end -0.7874 -0.4064)
			(stroke
				(width 0.1524)
				(type default)
			)
			(layer "F.SilkS")
		)
		(fp_line
			(start -0.12065 -0.305054)
			(end -0.12065 -0.2794)
			(stroke
				(width 0.1)
				(type default)
			)
			(layer "F.Fab")
		)
		(fp_line
			(start -0.67945 -0.305054)
			(end -0.12065 -0.305054)
			(stroke
				(width 0.1)
				(type default)
			)
			(layer "F.Fab")
		)
		(fp_line
			(start 0.67945 -0.3048)
			(end 0.67945 0.3048)
			(stroke
				(width 0.1)
				(type default)
			)
			(layer "F.Fab")
		)
		(fp_line
			(start 0.12065 -0.3048)
			(end 0.67945 -0.3048)
			(stroke
				(width 0.1)
				(type default)
			)
			(layer "F.Fab")
		)
		(fp_line
			(start 0.12065 -0.2794)
			(end 0.12065 -0.3048)
			(stroke
				(width 0.1)
				(type default)
			)
			(layer "F.Fab")
		)
		(fp_line
			(start -0.12065 -0.2794)
			(end 0.12065 -0.2794)
			(stroke
				(width 0.1)
				(type default)
			)
			(layer "F.Fab")
		)
		(fp_line
			(start 0.120396 0.2794)
			(end -0.12065 0.2794)
			(stroke
				(width 0.1)
				(type default)
			)
			(layer "F.Fab")
		)
		(fp_line
			(start -0.12065 0.2794)
			(end -0.12065 0.3048)
			(stroke
				(width 0.1)
				(type default)
			)
			(layer "F.Fab")
		)
		(fp_line
			(start 0.67945 0.3048)
			(end 0.120396 0.3048)
			(stroke
				(width 0.1)
				(type default)
			)
			(layer "F.Fab")
		)
		(fp_line
			(start 0.120396 0.3048)
			(end 0.120396 0.2794)
			(stroke
				(width 0.1)
				(type default)
			)
			(layer "F.Fab")
		)
		(fp_line
			(start -0.12065 0.3048)
			(end -0.67945 0.3048)
			(stroke
				(width 0.1)
				(type default)
			)
			(layer "F.Fab")
		)
		(fp_line
			(start -0.67945 0.3048)
			(end -0.67945 -0.305054)
			(stroke
				(width 0.1)
				(type default)
			)
			(layer "F.Fab")
		)
		(pad "1" smd circle
			(at -0.40005 0 90)
			(size 0 0)
			(layers "F.Cu" "F.Mask" "F.Paste")
			(net "I3C_MB_BMC_R_SCL")
		)
		(pad "2" smd circle
			(at 0.40005 0 90)
			(size 0 0)
			(layers "F.Cu" "F.Mask" "F.Paste")
			(net "I3C_MB_BMC_SCL")
		)
	)
	(footprint ""
		(layer "F.Cu")
		(at 262.281924 -280.189432 180)
		(property "Reference" "C3421"
			(at 0 0 180)
			(layer "F.SilkS")
			(hide yes)
			(effects
				(font
					(size 1.27 1.27)
				)
			)
		)
		(property "Value" ""
			(at 0 0 180)
			(layer "F.Fab")
			(effects
				(font
					(size 1.27 1.27)
				)
			)
		)
		(duplicate_pad_numbers_are_jumpers no)
		(fp_line
			(start 1.2954 0.5842)
			(end -1.2954 0.5842)
			(stroke
				(width 0.1524)
				(type default)
			)
			(layer "F.SilkS")
		)
		(fp_line
			(start 1.2954 -0.5842)
			(end 1.2954 0.5842)
			(stroke
				(width 0.1524)
				(type default)
			)
			(layer "F.SilkS")
		)
		(fp_line
			(start -1.2954 0.5842)
			(end -1.2954 -0.5842)
			(stroke
				(width 0.1524)
				(type default)
			)
			(layer "F.SilkS")
		)
		(fp_line
			(start -1.2954 -0.5842)
			(end 1.2954 -0.5842)
			(stroke
				(width 0.1524)
				(type default)
			)
			(layer "F.SilkS")
		)
		(fp_line
			(start 1.1938 0.4064)
			(end 0.8636 0.4064)
			(stroke
				(width 0.1)
				(type default)
			)
			(layer "F.Fab")
		)
		(fp_line
			(start 1.1938 -0.4064)
			(end 1.1938 0.4064)
			(stroke
				(width 0.1)
				(type default)
			)
			(layer "F.Fab")
		)
		(fp_line
			(start 0.8636 0.4572)
			(end -0.8636 0.4572)
			(stroke
				(width 0.1)
				(type default)
			)
			(layer "F.Fab")
		)
		(fp_line
			(start 0.8636 0.4064)
			(end 0.8636 0.4572)
			(stroke
				(width 0.1)
				(type default)
			)
			(layer "F.Fab")
		)
		(fp_line
			(start 0.8636 -0.4064)
			(end 1.1938 -0.4064)
			(stroke
				(width 0.1)
				(type default)
			)
			(layer "F.Fab")
		)
		(fp_line
			(start 0.8636 -0.4572)
			(end 0.8636 -0.4064)
			(stroke
				(width 0.1)
				(type default)
			)
			(layer "F.Fab")
		)
		(fp_line
			(start -0.8636 0.4572)
			(end -0.8636 0.4064)
			(stroke
				(width 0.1)
				(type default)
			)
			(layer "F.Fab")
		)
		(fp_line
			(start -0.8636 0.4064)
			(end -1.1938 0.4064)
			(stroke
				(width 0.1)
				(type default)
			)
			(layer "F.Fab")
		)
		(fp_line
			(start -0.8636 -0.4064)
			(end -0.8636 -0.4572)
			(stroke
				(width 0.1)
				(type default)
			)
			(layer "F.Fab")
		)
		(fp_line
			(start -0.8636 -0.4572)
			(end 0.8636 -0.4572)
			(stroke
				(width 0.1)
				(type default)
			)
			(layer "F.Fab")
		)
		(fp_line
			(start -1.1938 0.4064)
			(end -1.1938 -0.4064)
			(stroke
				(width 0.1)
				(type default)
			)
			(layer "F.Fab")
		)
		(fp_line
			(start -1.1938 -0.4064)
			(end -0.8636 -0.4064)
			(stroke
				(width 0.1)
				(type default)
			)
			(layer "F.Fab")
		)
		(pad "1" smd rect
			(at -0.7366 0 90)
			(size 0.7112 0.8128)
			(layers "F.Cu" "F.Mask" "F.Paste")
			(net "SYSPLL_VDDA18_PEX2_R")
		)
		(pad "2" smd rect
			(at 0.7366 0 90)
			(size 0.7112 0.8128)
			(layers "F.Cu" "F.Mask" "F.Paste")
			(net "GND")
		)
	)
	(footprint ""
		(layer "F.Cu")
		(at 369.189 -188.468)
		(property "Reference" "U344"
			(at -1.3462 -4.613148 0)
			(unlocked yes)
			(layer "F.SilkS")
			(effects
				(font
					(size 0.7874 0.5842)
					(thickness 0.1524)
				)
				(justify left)
			)
		)
		(property "Value" ""
			(at 0 0 0)
			(layer "F.Fab")
			(effects
				(font
					(size 1.27 1.27)
				)
			)
		)
		(duplicate_pad_numbers_are_jumpers no)
		(fp_line
			(start -2.097532 -3.949954)
			(end -2.097532 3.949954)
			(stroke
				(width 0.1524)
				(type default)
			)
			(layer "F.SilkS")
		)
		(fp_line
			(start -2.097532 3.949954)
			(end 2.097532 3.949954)
			(stroke
				(width 0.1524)
				(type default)
			)
			(layer "F.SilkS")
		)
		(fp_line
			(start -1.409954 -3.949954)
			(end -2.097532 -3.949954)
			(stroke
				(width 0.1524)
				(type default)
			)
			(layer "F.SilkS")
		)
		(fp_line
			(start 0 -2.54)
			(end -1.409954 -3.949954)
			(stroke
				(width 0.1524)
				(type default)
			)
			(layer "F.SilkS")
		)
		(fp_line
			(start 1.409954 -3.949954)
			(end 0 -2.54)
			(stroke
				(width 0.1524)
				(type default)
			)
			(layer "F.SilkS")
		)
		(fp_line
			(start 2.097532 -3.949954)
			(end 1.409954 -3.949954)
			(stroke
				(width 0.1524)
				(type default)
			)
			(layer "F.SilkS")
		)
		(fp_line
			(start 2.097532 3.949954)
			(end 2.097532 -3.949954)
			(stroke
				(width 0.1524)
				(type default)
			)
			(layer "F.SilkS")
		)
		(fp_poly
			(pts
				(xy -4.7498 -4.182872) (xy -4.7498 -3.166872) (xy -3.7338 -3.674872)
			)
			(stroke
				(width 0)
				(type default)
			)
			(fill yes)
			(layer "F.SilkS")
		)
		(fp_line
			(start -2.249932 -3.949954)
			(end -2.249932 3.949954)
			(stroke
				(width 0.1)
				(type default)
			)
			(layer "F.Fab")
		)
		(fp_line
			(start -2.249932 3.949954)
			(end 2.249932 3.949954)
			(stroke
				(width 0.1)
				(type default)
			)
			(layer "F.Fab")
		)
		(fp_line
			(start 2.249932 -3.949954)
			(end -2.249932 -3.949954)
			(stroke
				(width 0.1)
				(type default)
			)
			(layer "F.Fab")
		)
		(fp_line
			(start 2.249932 3.949954)
			(end 2.249932 -3.949954)
			(stroke
				(width 0.1)
				(type default)
			)
			(layer "F.Fab")
		)
		(fp_poly
			(pts
				(xy -4.7498 -4.182872) (xy -4.7498 -3.166872) (xy -3.7338 -3.674872)
			)
			(stroke
				(width 0)
				(type default)
			)
			(fill yes)
			(layer "F.Fab")
		)
		(pad "1" smd rect
			(at -2.925064 -3.674872 270)
			(size 0.6096 1.3716)
			(layers "F.Cu" "F.Mask" "F.Paste")
			(net "PEX0_PCA9555_1_INT_N")
		)
		(pad "2" smd rect
			(at -2.925064 -2.925064 270)
			(size 0.4064 1.3716)
			(layers "F.Cu" "F.Mask" "F.Paste")
			(net "PCA9555_1_PEX0_A1")
		)
		(pad "3" smd rect
			(at -2.925064 -2.275078 270)
			(size 0.4064 1.3716)
			(layers "F.Cu" "F.Mask" "F.Paste")
			(net "PCA9555_1_PEX0_A2")
		)
		(pad "4" smd rect
			(at -2.925064 -1.625092 270)
			(size 0.4064 1.3716)
			(layers "F.Cu" "F.Mask" "F.Paste")
			(net "PRSNT_SSD2_FPGA_PCA9555_N")
		)
		(pad "5" smd rect
			(at -2.925064 -0.975106 270)
			(size 0.4064 1.3716)
			(layers "F.Cu" "F.Mask" "F.Paste")
			(net "SSD2_PEX_PWR_EN")
		)
		(pad "6" smd rect
			(at -2.925064 -0.32512 270)
			(size 0.4064 1.3716)
			(layers "F.Cu" "F.Mask" "F.Paste")
			(net "RST_PEX_SSD2_PERST_N")
		)
		(pad "7" smd rect
			(at -2.925064 0.32512 270)
			(size 0.4064 1.3716)
			(layers "F.Cu" "F.Mask" "F.Paste")
			(net "Net_1168")
		)
		(pad "8" smd rect
			(at -2.925064 0.975106 270)
			(size 0.4064 1.3716)
			(layers "F.Cu" "F.Mask" "F.Paste")
			(net "PRSNT_SSD3_FPGA_PCA9555_N")
		)
		(pad "9" smd rect
			(at -2.925064 1.625092 270)
			(size 0.4064 1.3716)
			(layers "F.Cu" "F.Mask" "F.Paste")
			(net "SSD3_PEX_PWR_EN")
		)
		(pad "10" smd rect
			(at -2.925064 2.275078 270)
			(size 0.4064 1.3716)
			(layers "F.Cu" "F.Mask" "F.Paste")
			(net "RST_PEX_SSD3_PERST_N")
		)
		(pad "11" smd rect
			(at -2.925064 2.925064 270)
			(size 0.4064 1.3716)
			(layers "F.Cu" "F.Mask" "F.Paste")
			(net "Net_1166")
		)
		(pad "12" smd rect
			(at -2.925064 3.674872 270)
			(size 0.6096 1.3716)
			(layers "F.Cu" "F.Mask" "F.Paste")
			(net "GND")
		)
		(pad "13" smd rect
			(at 2.925064 3.674872 270)
			(size 0.6096 1.3716)
			(layers "F.Cu" "F.Mask" "F.Paste")
			(net "PRSNT_NIC1_FPGA_PCA9555_N")
		)
		(pad "14" smd rect
			(at 2.925064 2.925064 270)
			(size 0.4064 1.3716)
			(layers "F.Cu" "F.Mask" "F.Paste")
			(net "NIC1_PEX_PWR_EN")
		)
		(pad "15" smd rect
			(at 2.925064 2.275078 270)
			(size 0.4064 1.3716)
			(layers "F.Cu" "F.Mask" "F.Paste")
			(net "RST_PEX_NIC1_PERST_N")
		)
		(pad "16" smd rect
			(at 2.925064 1.625092 270)
			(size 0.4064 1.3716)
			(layers "F.Cu" "F.Mask" "F.Paste")
			(net "Net_1167")
		)
		(pad "17" smd rect
			(at 2.925064 0.975106 270)
			(size 0.4064 1.3716)
			(layers "F.Cu" "F.Mask" "F.Paste")
			(net "Net_8988")
		)
		(pad "18" smd rect
			(at 2.925064 0.32512 270)
			(size 0.4064 1.3716)
			(layers "F.Cu" "F.Mask" "F.Paste")
			(net "Net_8987")
		)
		(pad "19" smd rect
			(at 2.925064 -0.32512 270)
			(size 0.4064 1.3716)
			(layers "F.Cu" "F.Mask" "F.Paste")
			(net "Net_8986")
		)
		(pad "20" smd rect
			(at 2.925064 -0.975106 270)
			(size 0.4064 1.3716)
			(layers "F.Cu" "F.Mask" "F.Paste")
			(net "Net_8985")
		)
		(pad "21" smd rect
			(at 2.925064 -1.625092 270)
			(size 0.4064 1.3716)
			(layers "F.Cu" "F.Mask" "F.Paste")
			(net "PCA9555_1_PEX0_A0")
		)
		(pad "22" smd rect
			(at 2.925064 -2.275078 270)
			(size 0.4064 1.3716)
			(layers "F.Cu" "F.Mask" "F.Paste")
			(net "SMB_PEX0_PCA9555_SCL")
		)
		(pad "23" smd rect
			(at 2.925064 -2.925064 270)
			(size 0.4064 1.3716)
			(layers "F.Cu" "F.Mask" "F.Paste")
			(net "SMB_PEX0_PCA9555_SDA")
		)
		(pad "24" smd rect
			(at 2.925064 -3.674872 270)
			(size 0.6096 1.3716)
			(layers "F.Cu" "F.Mask" "F.Paste")
			(net "P3V3_AUX")
		)
	)
	(footprint ""
		(layer "F.Cu")
		(at 143.764762 -239.853978 -90)
		(property "Reference" "C4420"
			(at 0 0 270)
			(layer "F.SilkS")
			(hide yes)
			(effects
				(font
					(size 1.27 1.27)
				)
			)
		)
		(property "Value" ""
			(at 0 0 270)
			(layer "F.Fab")
			(effects
				(font
					(size 1.27 1.27)
				)
			)
		)
		(duplicate_pad_numbers_are_jumpers no)
		(fp_line
			(start -1.524 0.762)
			(end -1.524 -0.762)
			(stroke
				(width 0.1524)
				(type default)
			)
			(layer "F.SilkS")
		)
		(fp_line
			(start 1.524 0.762)
			(end -1.524 0.762)
			(stroke
				(width 0.1524)
				(type default)
			)
			(layer "F.SilkS")
		)
		(fp_line
			(start -1.524 -0.762)
			(end 1.524 -0.762)
			(stroke
				(width 0.1524)
				(type default)
			)
			(layer "F.SilkS")
		)
		(fp_line
			(start 1.524 -0.762)
			(end 1.524 0.762)
			(stroke
				(width 0.1524)
				(type default)
			)
			(layer "F.SilkS")
		)
		(fp_line
			(start -1.1049 0.724916)
			(end 1.1049 0.724916)
			(stroke
				(width 0.1)
				(type default)
			)
			(layer "F.Fab")
		)
		(fp_line
			(start 1.1049 0.724916)
			(end 1.1049 -0.724916)
			(stroke
				(width 0.1)
				(type default)
			)
			(layer "F.Fab")
		)
		(fp_line
			(start -1.1049 -0.724916)
			(end -1.1049 0.724916)
			(stroke
				(width 0.1)
				(type default)
			)
			(layer "F.Fab")
		)
		(fp_line
			(start 1.1049 -0.724916)
			(end -1.1049 -0.724916)
			(stroke
				(width 0.1)
				(type default)
			)
			(layer "F.Fab")
		)
		(pad "1" smd rect
			(at -0.889 0 90)
			(size 1.016 1.27)
			(layers "F.Cu" "F.Mask" "F.Paste")
			(net "P3V3_AUX")
		)
		(pad "2" smd rect
			(at 0.889 0 90)
			(size 1.016 1.27)
			(layers "F.Cu" "F.Mask" "F.Paste")
			(net "GND")
		)
	)
	(footprint ""
		(layer "F.Cu")
		(at 284.226 -84.836 180)
		(property "Reference" "R485"
			(at 0 0 180)
			(layer "F.SilkS")
			(hide yes)
			(effects
				(font
					(size 1.27 1.27)
				)
			)
		)
		(property "Value" ""
			(at 0 0 180)
			(layer "F.Fab")
			(effects
				(font
					(size 1.27 1.27)
				)
			)
		)
		(duplicate_pad_numbers_are_jumpers no)
		(fp_line
			(start 0.7874 0.4064)
			(end -0.7874 0.4064)
			(stroke
				(width 0.1524)
				(type default)
			)
			(layer "F.SilkS")
		)
		(fp_line
			(start 0.7874 -0.4064)
			(end 0.7874 0.4064)
			(stroke
				(width 0.1524)
				(type default)
			)
			(layer "F.SilkS")
		)
		(fp_line
			(start -0.7874 0.4064)
			(end -0.7874 -0.4064)
			(stroke
				(width 0.1524)
				(type default)
			)
			(layer "F.SilkS")
		)
		(fp_line
			(start -0.7874 -0.4064)
			(end 0.7874 -0.4064)
			(stroke
				(width 0.1524)
				(type default)
			)
			(layer "F.SilkS")
		)
		(fp_line
			(start 0.67945 0.3048)
			(end 0.120396 0.3048)
			(stroke
				(width 0.1)
				(type default)
			)
			(layer "F.Fab")
		)
		(fp_line
			(start 0.67945 -0.3048)
			(end 0.67945 0.3048)
			(stroke
				(width 0.1)
				(type default)
			)
			(layer "F.Fab")
		)
		(fp_line
			(start 0.12065 -0.2794)
			(end 0.12065 -0.3048)
			(stroke
				(width 0.1)
				(type default)
			)
			(layer "F.Fab")
		)
		(fp_line
			(start 0.12065 -0.3048)
			(end 0.67945 -0.3048)
			(stroke
				(width 0.1)
				(type default)
			)
			(layer "F.Fab")
		)
		(fp_line
			(start 0.120396 0.3048)
			(end 0.120396 0.2794)
			(stroke
				(width 0.1)
				(type default)
			)
			(layer "F.Fab")
		)
		(fp_line
			(start 0.120396 0.2794)
			(end -0.12065 0.2794)
			(stroke
				(width 0.1)
				(type default)
			)
			(layer "F.Fab")
		)
		(fp_line
			(start -0.12065 0.3048)
			(end -0.67945 0.3048)
			(stroke
				(width 0.1)
				(type default)
			)
			(layer "F.Fab")
		)
		(fp_line
			(start -0.12065 0.2794)
			(end -0.12065 0.3048)
			(stroke
				(width 0.1)
				(type default)
			)
			(layer "F.Fab")
		)
		(fp_line
			(start -0.12065 -0.2794)
			(end 0.12065 -0.2794)
			(stroke
				(width 0.1)
				(type default)
			)
			(layer "F.Fab")
		)
		(fp_line
			(start -0.12065 -0.305054)
			(end -0.12065 -0.2794)
			(stroke
				(width 0.1)
				(type default)
			)
			(layer "F.Fab")
		)
		(fp_line
			(start -0.67945 0.3048)
			(end -0.67945 -0.305054)
			(stroke
				(width 0.1)
				(type default)
			)
			(layer "F.Fab")
		)
		(fp_line
			(start -0.67945 -0.305054)
			(end -0.12065 -0.305054)
			(stroke
				(width 0.1)
				(type default)
			)
			(layer "F.Fab")
		)
		(pad "1" smd circle
			(at -0.40005 0 180)
			(size 0 0)
			(layers "F.Cu" "F.Mask" "F.Paste")
			(net "BB_FRU_A1")
		)
		(pad "2" smd circle
			(at 0.40005 0 180)
			(size 0 0)
			(layers "F.Cu" "F.Mask" "F.Paste")
			(net "P3V3_AUX")
		)
	)
)
